(kicad_pcb
	(version 20260206)
	(generator "pcbnew")
	(generator_version "10.0")
	(general
		(thickness 1.6)
		(legacy_teardrops no)
	)
	(paper "A4")
	(title_block
		(title "baseboard — 13948-1b.1110WZS1818.brd")
		(comment 1 "Honey Badger (Wiwynn) / footprints 502-508 of 2523")
	)
	(layers
		(0 "F.Cu" signal "TOP")
		(4 "In1.Cu" signal "L2GND")
		(6 "In2.Cu" signal "L3")
		(8 "In3.Cu" signal "L4VCC")
		(10 "In4.Cu" signal "L5VCC")
		(12 "In5.Cu" signal "L6")
		(14 "In6.Cu" signal "L7GND")
		(2 "B.Cu" signal "BOTTOM")
		(9 "F.Adhes" user "F.Adhesive")
		(11 "B.Adhes" user "B.Adhesive")
		(13 "F.Paste" user "Package Geometry/Pastemask Top")
		(15 "B.Paste" user "Package Geometry/Pastemask Bottom")
		(5 "F.SilkS" user "Ref Des/Silkscreen Top")
		(7 "B.SilkS" user "Ref Des/Silkscreen Bottom")
		(1 "F.Mask" user "Board Geometry/Soldermask Top")
		(3 "B.Mask" user "Board Geometry/Soldermask Bottom")
		(17 "Dwgs.User" user "User.Drawings")
		(19 "Cmts.User" user "User.Comments")
		(21 "Eco1.User" user "User.Eco1")
		(23 "Eco2.User" user "User.Eco2")
		(25 "Edge.Cuts" user "Board Geometry/Outline")
		(27 "Margin" user)
		(31 "F.CrtYd" user "Package Geometry/Place Bound Top")
		(29 "B.CrtYd" user "Package Geometry/Place Bound Bottom")
		(35 "F.Fab" user "Ref Des/Assembly Top")
		(33 "B.Fab" user "Ref Des/Assembly Bottom")
	)
	(footprint ""
		(layer "F.Cu")
		(at 100.47097 -76.454)
		(property "Reference" "SR805"
			(at 0 0 0)
			(layer "F.SilkS")
			(hide yes)
			(effects
				(font
					(size 1.27 1.27)
				)
			)
		)
		(property "Value" "4K75R2F-1-GP"
			(at 0.064008 -3.993896 0)
			(unlocked yes)
			(layer "F.Fab")
			(hide yes)
			(effects
				(font
					(size 1.016 1.016)
					(thickness 0.1524)
				)
			)
		)
		(property "Device Type" "R402H16"
			(at 0.064008 -5.517896 0)
			(unlocked yes)
			(layer "F.Fab")
			(hide yes)
			(effects
				(font
					(size 1.016 1.016)
					(thickness 0.1524)
				)
			)
		)
		(duplicate_pad_numbers_are_jumpers no)
		(fp_line
			(start -0.508 -0.9398)
			(end -0.508 0.9398)
			(stroke
				(width 0.1524)
				(type default)
			)
			(layer "F.SilkS")
		)
		(fp_line
			(start 0.508 -0.9398)
			(end -0.508 -0.9398)
			(stroke
				(width 0.1524)
				(type default)
			)
			(layer "F.SilkS")
		)
		(fp_rect
			(start -0.508 0.9398)
			(end 0.508 -0.9398)
			(stroke
				(width 0)
				(type default)
			)
			(fill no)
			(layer "F.CrtYd")
		)
		(fp_rect
			(start -0.508 0.9398)
			(end 0.508 -0.9398)
			(stroke
				(width 0)
				(type default)
			)
			(fill no)
			(layer "F.Fab")
		)
		(pad "1" smd custom
			(at 0 -0.4445)
			(size 0.1397 0.1397)
			(layers "F.Cu" "F.Mask" "F.Paste")
			(net "EXP_IDDT")
			(options
				(clearance outline)
				(anchor circle)
			)
			(primitives
				(gr_poly
					(pts
						(arc
							(start -0.1778 -0.2794)
							(mid -0.249642 -0.249642)
							(end -0.2794 -0.1778)
						)
						(arc
							(start -0.2794 0.1778)
							(mid -0.249642 0.249642)
							(end -0.1778 0.2794)
						)
						(arc
							(start 0.1778 0.2794)
							(mid 0.249642 0.249642)
							(end 0.2794 0.1778)
						)
						(arc
							(start 0.2794 -0.1778)
							(mid 0.249642 -0.249642)
							(end 0.1778 -0.2794)
						)
					)
					(width 0)
					(fill yes)
				)
			)
		)
		(pad "2" smd custom
			(at 0 0.4445)
			(size 0.1397 0.1397)
			(layers "F.Cu" "F.Mask" "F.Paste")
			(net "GND")
			(options
				(clearance outline)
				(anchor circle)
			)
			(primitives
				(gr_poly
					(pts
						(arc
							(start -0.1778 -0.2794)
							(mid -0.249642 -0.249642)
							(end -0.2794 -0.1778)
						)
						(arc
							(start -0.2794 0.1778)
							(mid -0.249642 0.249642)
							(end -0.1778 0.2794)
						)
						(arc
							(start 0.1778 0.2794)
							(mid 0.249642 0.249642)
							(end 0.2794 0.1778)
						)
						(arc
							(start 0.2794 -0.1778)
							(mid 0.249642 -0.249642)
							(end 0.1778 -0.2794)
						)
					)
					(width 0)
					(fill yes)
				)
			)
		)
	)
	(footprint ""
		(layer "F.Cu")
		(at 48.26 -230.886)
		(property "Reference" "C274"
			(at 0 0 0)
			(layer "F.SilkS")
			(hide yes)
			(effects
				(font
					(size 1.27 1.27)
				)
			)
		)
		(property "Value" "SCD1U25V3KX-GP"
			(at 0 -2.8194 0)
			(unlocked yes)
			(layer "F.Fab")
			(hide yes)
			(effects
				(font
					(size 1.016 1.016)
					(thickness 0.1524)
				)
			)
		)
		(property "Device Type" "C603H36"
			(at 0 -4.3434 0)
			(unlocked yes)
			(layer "F.Fab")
			(hide yes)
			(effects
				(font
					(size 1.016 1.016)
					(thickness 0.1524)
				)
			)
		)
		(duplicate_pad_numbers_are_jumpers no)
		(fp_line
			(start 0.508 0)
			(end -0.508 0)
			(stroke
				(width 0.2032)
				(type default)
			)
			(layer "F.SilkS")
		)
		(fp_rect
			(start -0.5842 1.3335)
			(end 0.5842 -1.3335)
			(stroke
				(width 0)
				(type default)
			)
			(fill no)
			(layer "F.CrtYd")
		)
		(fp_rect
			(start -0.5842 1.3335)
			(end 0.5842 -1.3335)
			(stroke
				(width 0)
				(type default)
			)
			(fill no)
			(layer "F.Fab")
		)
		(pad "1" smd custom
			(at 0 -0.762)
			(size 0.2159 0.2159)
			(layers "F.Cu" "F.Mask" "F.Paste")
			(net "P12V_PCIE")
			(options
				(clearance outline)
				(anchor circle)
			)
			(primitives
				(gr_poly
					(pts
						(arc
							(start -0.3302 -0.4318)
							(mid -0.402042 -0.402042)
							(end -0.4318 -0.3302)
						)
						(arc
							(start -0.4318 0.3302)
							(mid -0.402042 0.402042)
							(end -0.3302 0.4318)
						)
						(arc
							(start 0.3302 0.4318)
							(mid 0.402042 0.402042)
							(end 0.4318 0.3302)
						)
						(arc
							(start 0.4318 -0.3302)
							(mid 0.402042 -0.402042)
							(end 0.3302 -0.4318)
						)
					)
					(width 0)
					(fill yes)
				)
			)
		)
		(pad "2" smd custom
			(at 0 0.762)
			(size 0.2159 0.2159)
			(layers "F.Cu" "F.Mask" "F.Paste")
			(net "GND")
			(options
				(clearance outline)
				(anchor circle)
			)
			(primitives
				(gr_poly
					(pts
						(arc
							(start -0.3302 -0.4318)
							(mid -0.402042 -0.402042)
							(end -0.4318 -0.3302)
						)
						(arc
							(start -0.4318 0.3302)
							(mid -0.402042 0.402042)
							(end -0.3302 0.4318)
						)
						(arc
							(start 0.3302 0.4318)
							(mid 0.402042 0.402042)
							(end 0.4318 0.3302)
						)
						(arc
							(start 0.4318 -0.3302)
							(mid 0.402042 -0.402042)
							(end 0.3302 -0.4318)
						)
					)
					(width 0)
					(fill yes)
				)
			)
		)
	)
	(footprint ""
		(layer "F.Cu")
		(at 220.17228 -87.85352 -90)
		(property "Reference" "U184"
			(at 0 0 270)
			(layer "F.SilkS")
			(hide yes)
			(effects
				(font
					(size 1.27 1.27)
				)
			)
		)
		(property "Value" "TXS0102DCUR-1-GP"
			(at 0 -11.1252 270)
			(unlocked yes)
			(layer "F.Fab")
			(hide yes)
			(effects
				(font
					(size 1.016 1.016)
					(thickness 0.1524)
				)
			)
		)
		(property "Device Type" "SSOIC8-4H36"
			(at 0 -12.6492 270)
			(unlocked yes)
			(layer "F.Fab")
			(hide yes)
			(effects
				(font
					(size 1.016 1.016)
					(thickness 0.1524)
				)
			)
		)
		(duplicate_pad_numbers_are_jumpers no)
		(fp_line
			(start -1.2573 2.1844)
			(end -1.2573 -2.1844)
			(stroke
				(width 0.1524)
				(type default)
			)
			(layer "F.SilkS")
		)
		(fp_line
			(start 1.2573 2.1844)
			(end -1.2573 2.1844)
			(stroke
				(width 0.1524)
				(type default)
			)
			(layer "F.SilkS")
		)
		(fp_line
			(start -1.2954 0.4572)
			(end -1.2954 2.159)
			(stroke
				(width 0.4064)
				(type default)
			)
			(layer "F.SilkS")
		)
		(fp_line
			(start -1.2065 0.2667)
			(end -1.27 0.2667)
			(stroke
				(width 0.1524)
				(type default)
			)
			(layer "F.SilkS")
		)
		(fp_line
			(start -0.9017 -0.0381)
			(end -1.2065 0.2667)
			(stroke
				(width 0.1524)
				(type default)
			)
			(layer "F.SilkS")
		)
		(fp_line
			(start -1.2573 -0.3556)
			(end -1.2192 -0.3556)
			(stroke
				(width 0.1524)
				(type default)
			)
			(layer "F.SilkS")
		)
		(fp_line
			(start -1.2192 -0.3556)
			(end -0.9017 -0.0381)
			(stroke
				(width 0.1524)
				(type default)
			)
			(layer "F.SilkS")
		)
		(fp_line
			(start -1.2573 -2.1844)
			(end 1.2573 -2.1844)
			(stroke
				(width 0.1524)
				(type default)
			)
			(layer "F.SilkS")
		)
		(fp_line
			(start 1.2573 -2.1844)
			(end 1.2573 2.1844)
			(stroke
				(width 0.1524)
				(type default)
			)
			(layer "F.SilkS")
		)
		(fp_poly
			(pts
				(xy -1.5113 2.4384) (xy 1.5113 2.4384) (xy 1.5113 -2.4384) (xy -1.5113 -2.4384)
			)
			(stroke
				(width 0)
				(type default)
			)
			(fill no)
			(layer "F.CrtYd")
		)
		(fp_poly
			(pts
				(xy -1.5113 -2.4384) (xy 1.5113 -2.4384) (xy 1.5113 2.4384) (xy -1.5113 2.4384)
			)
			(stroke
				(width 0)
				(type default)
			)
			(fill no)
			(layer "F.Fab")
		)
		(pad "1" smd rect
			(at -0.75057 1.1684 270)
			(size 0.3048 1.524)
			(layers "F.Cu" "F.Mask" "F.Paste")
			(net "IOC_UART_R_RX")
		)
		(pad "2" smd rect
			(at -0.25019 1.1684 270)
			(size 0.3048 1.524)
			(layers "F.Cu" "F.Mask" "F.Paste")
			(net "GND")
		)
		(pad "3" smd rect
			(at 0.25019 1.1684 270)
			(size 0.3048 1.524)
			(layers "F.Cu" "F.Mask" "F.Paste")
			(net "P1V8_C")
		)
		(pad "4" smd rect
			(at 0.75057 1.1684 270)
			(size 0.3048 1.524)
			(layers "F.Cu" "F.Mask" "F.Paste")
			(net "IOC_UART_0_RX_R")
		)
		(pad "5" smd rect
			(at 0.75057 -1.1684 270)
			(size 0.3048 1.524)
			(layers "F.Cu" "F.Mask" "F.Paste")
			(net "IOC_UART_0_TX_R")
		)
		(pad "6" smd rect
			(at 0.25019 -1.1684 270)
			(size 0.3048 1.524)
			(layers "F.Cu" "F.Mask" "F.Paste")
			(net "SYS_RST_N_0")
		)
		(pad "7" smd rect
			(at -0.25019 -1.1684 270)
			(size 0.3048 1.524)
			(layers "F.Cu" "F.Mask" "F.Paste")
			(net "P3V3_STBY")
		)
		(pad "8" smd rect
			(at -0.75057 -1.1684 270)
			(size 0.3048 1.524)
			(layers "F.Cu" "F.Mask" "F.Paste")
			(net "IOC_UART_R_TX")
		)
	)
	(footprint ""
		(layer "F.Cu")
		(at 95.89897 -89.662 -90)
		(property "Reference" "SR798"
			(at 0 0 270)
			(layer "F.SilkS")
			(hide yes)
			(effects
				(font
					(size 1.27 1.27)
				)
			)
		)
		(property "Value" "4K75R2F-1-GP"
			(at 0.064008 -3.993896 270)
			(unlocked yes)
			(layer "F.Fab")
			(hide yes)
			(effects
				(font
					(size 1.016 1.016)
					(thickness 0.1524)
				)
			)
		)
		(property "Device Type" "R402H16"
			(at 0.064008 -5.517896 270)
			(unlocked yes)
			(layer "F.Fab")
			(hide yes)
			(effects
				(font
					(size 1.016 1.016)
					(thickness 0.1524)
				)
			)
		)
		(duplicate_pad_numbers_are_jumpers no)
		(fp_line
			(start -0.508 -0.9398)
			(end -0.508 0.9398)
			(stroke
				(width 0.1524)
				(type default)
			)
			(layer "F.SilkS")
		)
		(fp_line
			(start 0.508 -0.9398)
			(end -0.508 -0.9398)
			(stroke
				(width 0.1524)
				(type default)
			)
			(layer "F.SilkS")
		)
		(fp_rect
			(start -0.508 0.9398)
			(end 0.508 -0.9398)
			(stroke
				(width 0)
				(type default)
			)
			(fill no)
			(layer "F.CrtYd")
		)
		(fp_rect
			(start -0.508 0.9398)
			(end 0.508 -0.9398)
			(stroke
				(width 0)
				(type default)
			)
			(fill no)
			(layer "F.Fab")
		)
		(pad "1" smd custom
			(at 0 -0.4445 270)
			(size 0.1397 0.1397)
			(layers "F.Cu" "F.Mask" "F.Paste")
			(net "EXP_CLK_SEL0")
			(options
				(clearance outline)
				(anchor circle)
			)
			(primitives
				(gr_poly
					(pts
						(arc
							(start -0.1778 -0.2794)
							(mid -0.249642 -0.249642)
							(end -0.2794 -0.1778)
						)
						(arc
							(start -0.2794 0.1778)
							(mid -0.249642 0.249642)
							(end -0.1778 0.2794)
						)
						(arc
							(start 0.1778 0.2794)
							(mid 0.249642 0.249642)
							(end 0.2794 0.1778)
						)
						(arc
							(start 0.2794 -0.1778)
							(mid 0.249642 -0.249642)
							(end 0.1778 -0.2794)
						)
					)
					(width 0)
					(fill yes)
				)
			)
		)
		(pad "2" smd custom
			(at 0 0.4445 270)
			(size 0.1397 0.1397)
			(layers "F.Cu" "F.Mask" "F.Paste")
			(net "GND")
			(options
				(clearance outline)
				(anchor circle)
			)
			(primitives
				(gr_poly
					(pts
						(arc
							(start -0.1778 -0.2794)
							(mid -0.249642 -0.249642)
							(end -0.2794 -0.1778)
						)
						(arc
							(start -0.2794 0.1778)
							(mid -0.249642 0.249642)
							(end -0.1778 0.2794)
						)
						(arc
							(start 0.1778 0.2794)
							(mid 0.249642 0.249642)
							(end 0.2794 0.1778)
						)
						(arc
							(start 0.2794 -0.1778)
							(mid 0.249642 -0.249642)
							(end 0.1778 -0.2794)
						)
					)
					(width 0)
					(fill yes)
				)
			)
		)
	)
	(footprint ""
		(layer "F.Cu")
		(at 8.078216 -224.97288 -90)
		(property "Reference" "R537"
			(at 0 0 270)
			(layer "F.SilkS")
			(hide yes)
			(effects
				(font
					(size 1.27 1.27)
				)
			)
		)
		(property "Value" "0R2J-2-GP"
			(at 0.064008 -3.993896 270)
			(unlocked yes)
			(layer "F.Fab")
			(hide yes)
			(effects
				(font
					(size 1.016 1.016)
					(thickness 0.1524)
				)
			)
		)
		(property "Device Type" "R402H16"
			(at 0.064008 -5.517896 270)
			(unlocked yes)
			(layer "F.Fab")
			(hide yes)
			(effects
				(font
					(size 1.016 1.016)
					(thickness 0.1524)
				)
			)
		)
		(duplicate_pad_numbers_are_jumpers no)
		(fp_line
			(start -0.508 -0.9398)
			(end -0.508 0.9398)
			(stroke
				(width 0.1524)
				(type default)
			)
			(layer "F.SilkS")
		)
		(fp_line
			(start 0.508 -0.9398)
			(end -0.508 -0.9398)
			(stroke
				(width 0.1524)
				(type default)
			)
			(layer "F.SilkS")
		)
		(fp_rect
			(start -0.508 0.9398)
			(end 0.508 -0.9398)
			(stroke
				(width 0)
				(type default)
			)
			(fill no)
			(layer "F.CrtYd")
		)
		(fp_rect
			(start -0.508 0.9398)
			(end 0.508 -0.9398)
			(stroke
				(width 0)
				(type default)
			)
			(fill no)
			(layer "F.Fab")
		)
		(pad "1" smd custom
			(at 0 -0.4445 270)
			(size 0.1397 0.1397)
			(layers "F.Cu" "F.Mask" "F.Paste")
			(net "PEER_TRAY_BMC")
			(options
				(clearance outline)
				(anchor circle)
			)
			(primitives
				(gr_poly
					(pts
						(arc
							(start -0.1778 -0.2794)
							(mid -0.249642 -0.249642)
							(end -0.2794 -0.1778)
						)
						(arc
							(start -0.2794 0.1778)
							(mid -0.249642 0.249642)
							(end -0.1778 0.2794)
						)
						(arc
							(start 0.1778 0.2794)
							(mid 0.249642 0.249642)
							(end 0.2794 0.1778)
						)
						(arc
							(start 0.2794 -0.1778)
							(mid 0.249642 -0.249642)
							(end 0.1778 -0.2794)
						)
					)
					(width 0)
					(fill yes)
				)
			)
		)
		(pad "2" smd custom
			(at 0 0.4445 270)
			(size 0.1397 0.1397)
			(layers "F.Cu" "F.Mask" "F.Paste")
			(net "PEER_TRAY_R")
			(options
				(clearance outline)
				(anchor circle)
			)
			(primitives
				(gr_poly
					(pts
						(arc
							(start -0.1778 -0.2794)
							(mid -0.249642 -0.249642)
							(end -0.2794 -0.1778)
						)
						(arc
							(start -0.2794 0.1778)
							(mid -0.249642 0.249642)
							(end -0.1778 0.2794)
						)
						(arc
							(start 0.1778 0.2794)
							(mid 0.249642 0.249642)
							(end 0.2794 0.1778)
						)
						(arc
							(start 0.2794 -0.1778)
							(mid 0.249642 -0.249642)
							(end 0.1778 -0.2794)
						)
					)
					(width 0)
					(fill yes)
				)
			)
		)
	)
	(footprint ""
		(layer "F.Cu")
		(at 78.8924 -9.1948 90)
		(property "Reference" "PC204"
			(at 0 0 90)
			(layer "F.SilkS")
			(hide yes)
			(effects
				(font
					(size 1.27 1.27)
				)
			)
		)
		(property "Value" "SC10U25V6KX-1GP"
			(at -0.0762 -5.1308 90)
			(unlocked yes)
			(layer "F.Fab")
			(hide yes)
			(effects
				(font
					(size 1.016 1.016)
					(thickness 0.1524)
				)
			)
		)
		(property "Device Type" "C1206H71"
			(at -0.127 -6.6548 90)
			(unlocked yes)
			(layer "F.Fab")
			(hide yes)
			(effects
				(font
					(size 1.016 1.016)
					(thickness 0.1524)
				)
			)
		)
		(duplicate_pad_numbers_are_jumpers no)
		(fp_line
			(start 1.016 -2.2352)
			(end 1.016 -0.8382)
			(stroke
				(width 0.1524)
				(type default)
			)
			(layer "F.SilkS")
		)
		(fp_line
			(start -1.016 -2.2352)
			(end 1.016 -2.2352)
			(stroke
				(width 0.1524)
				(type default)
			)
			(layer "F.SilkS")
		)
		(fp_line
			(start -1.016 -0.8382)
			(end -1.016 -2.2352)
			(stroke
				(width 0.1524)
				(type default)
			)
			(layer "F.SilkS")
		)
		(fp_line
			(start 1.016 0.8382)
			(end 1.016 2.2352)
			(stroke
				(width 0.1524)
				(type default)
			)
			(layer "F.SilkS")
		)
		(fp_line
			(start 1.016 2.2352)
			(end -1.016 2.2352)
			(stroke
				(width 0.1524)
				(type default)
			)
			(layer "F.SilkS")
		)
		(fp_line
			(start -1.016 2.2352)
			(end -1.016 0.8382)
			(stroke
				(width 0.1524)
				(type default)
			)
			(layer "F.SilkS")
		)
		(fp_rect
			(start -1.0922 2.3114)
			(end 1.0922 -2.3114)
			(stroke
				(width 0)
				(type default)
			)
			(fill no)
			(layer "F.CrtYd")
		)
		(fp_poly
			(pts
				(xy 1.0922 -2.3114) (xy 1.0922 2.3114) (xy -1.0922 2.3114) (xy -1.0922 -2.3114)
			)
			(stroke
				(width 0)
				(type default)
			)
			(fill no)
			(layer "F.Fab")
		)
		(pad "1" smd rect
			(at 0 -1.397 90)
			(size 1.651 1.27)
			(layers "F.Cu" "F.Mask" "F.Paste")
			(net "VT235_VDDH")
		)
		(pad "2" smd rect
			(at 0 1.397 90)
			(size 1.651 1.27)
			(layers "F.Cu" "F.Mask" "F.Paste")
			(net "GND")
		)
	)
	(footprint ""
		(layer "F.Cu")
		(at 293.819072 -191.842136)
		(property "Reference" "C178"
			(at 0 0 0)
			(layer "F.SilkS")
			(hide yes)
			(effects
				(font
					(size 1.27 1.27)
				)
			)
		)
		(property "Value" "SCD1U16V2KX-3GP"
			(at 1.1811 -2.7051 0)
			(unlocked yes)
			(layer "F.Fab")
			(hide yes)
			(effects
				(font
					(size 1.016 1.016)
					(thickness 0.1524)
				)
			)
		)
		(property "Device Type" "C402H22"
			(at 1.1811 -4.2291 0)
			(unlocked yes)
			(layer "F.Fab")
			(hide yes)
			(effects
				(font
					(size 1.016 1.016)
					(thickness 0.1524)
				)
			)
		)
		(duplicate_pad_numbers_are_jumpers no)
		(fp_rect
			(start -0.4318 0.9525)
			(end 0.4318 -0.9525)
			(stroke
				(width 0)
				(type default)
			)
			(fill no)
			(layer "F.CrtYd")
		)
		(fp_rect
			(start -0.4318 0.9525)
			(end 0.4318 -0.9525)
			(stroke
				(width 0)
				(type default)
			)
			(fill no)
			(layer "F.Fab")
		)
		(pad "1" smd custom
			(at 0 -0.4445)
			(size 0.1524 0.1524)
			(layers "F.Cu" "F.Mask" "F.Paste")
			(net "P1V53_STBY")
			(options
				(clearance outline)
				(anchor circle)
			)
			(primitives
				(gr_poly
					(pts
						(arc
							(start 0.3048 -0.2032)
							(mid 0.275042 -0.275042)
							(end 0.2032 -0.3048)
						)
						(arc
							(start -0.2032 -0.3048)
							(mid -0.275042 -0.275042)
							(end -0.3048 -0.2032)
						)
						(arc
							(start -0.3048 0.2032)
							(mid -0.275042 0.275042)
							(end -0.2032 0.3048)
						)
						(arc
							(start 0.2032 0.3048)
							(mid 0.275042 0.275042)
							(end 0.3048 0.2032)
						)
					)
					(width 0)
					(fill yes)
				)
			)
		)
		(pad "2" smd custom
			(at 0 0.4445)
			(size 0.1524 0.1524)
			(layers "F.Cu" "F.Mask" "F.Paste")
			(net "GND")
			(options
				(clearance outline)
				(anchor circle)
			)
			(primitives
				(gr_poly
					(pts
						(arc
							(start 0.3048 -0.2032)
							(mid 0.275042 -0.275042)
							(end 0.2032 -0.3048)
						)
						(arc
							(start -0.2032 -0.3048)
							(mid -0.275042 -0.275042)
							(end -0.3048 -0.2032)
						)
						(arc
							(start -0.3048 0.2032)
							(mid -0.275042 0.275042)
							(end -0.2032 0.3048)
						)
						(arc
							(start 0.2032 0.3048)
							(mid 0.275042 0.275042)
							(end 0.3048 0.2032)
						)
					)
					(width 0)
					(fill yes)
				)
			)
		)
	)
)
